(kicad_pcb
	(version 20241229)
	(generator "pcbnew")
	(generator_version "9.0")
	(general
		(thickness 1.6642)
		(legacy_teardrops no)
	)
	(paper "A3")
	(title_block
		(title "PolarFire SoM")
		(date "2025-07-22")
		(rev "1.1.4")
		(company "Antmicro Ltd")
		(comment 1 "www.antmicro.com")
		(comment 9 "footprints 161-164 of 470")
	)
	(layers
		(0 "F.Cu" mixed)
		(4 "In1.Cu" power)
		(6 "In2.Cu" signal)
		(8 "In3.Cu" power)
		(10 "In4.Cu" signal)
		(12 "In5.Cu" power)
		(14 "In6.Cu" power)
		(16 "In7.Cu" signal)
		(18 "In8.Cu" power)
		(20 "In9.Cu" signal)
		(22 "In10.Cu" power)
		(24 "In11.Cu" signal)
		(26 "In12.Cu" signal)
		(2 "B.Cu" mixed)
		(9 "F.Adhes" user "F.Adhesive")
		(11 "B.Adhes" user "B.Adhesive")
		(13 "F.Paste" user)
		(15 "B.Paste" user)
		(5 "F.SilkS" user "F.Silkscreen")
		(7 "B.SilkS" user "B.Silkscreen")
		(1 "F.Mask" user)
		(3 "B.Mask" user)
		(17 "Dwgs.User" user "User.Drawings")
		(19 "Cmts.User" user "User.Comments")
		(21 "Eco1.User" user "User.Eco1")
		(23 "Eco2.User" user "User.Eco2")
		(25 "Edge.Cuts" user)
		(27 "Margin" user)
		(31 "F.CrtYd" user "F.Courtyard")
		(29 "B.CrtYd" user "B.Courtyard")
		(35 "F.Fab" user)
		(33 "B.Fab" user)
	)
	(footprint "antmicro-footprints:R_0402_1005Metric"
		(layer "B.Cu")
		(at 220.7175 144.895 90)
		(descr "Resistor SMD 0402")
		(tags "resistor SMD 0402")
		(property "Reference" "R147"
			(at 9.93 7.3275 270)
			(layer "B.SilkS")
			(effects
				(font
					(size 0.7 0.7)
					(thickness 0.15)
				)
				(justify left bottom mirror)
			)
		)
		(property "Value" "R_10k_0402"
			(at -1.011843 -1.772047 270)
			(layer "B.Fab")
			(hide yes)
			(effects
				(font
					(size 0.7 0.7)
					(thickness 0.15)
				)
				(justify left bottom mirror)
			)
		)
		(property "Datasheet" "https://www.bourns.com/docs/product-datasheets/cr.pdf"
			(at 0 0 90)
			(layer "F.Fab")
			(hide yes)
			(effects
				(font
					(size 1.27 1.27)
					(thickness 0.15)
				)
			)
		)
		(property "Description" "SMD Chip Resistor, 10 kohm, ± 1%, 62.5 mW, 0402 [1005 Metric], Thick Film, General Purpose"
			(at 0 0 90)
			(layer "F.Fab")
			(hide yes)
			(effects
				(font
					(size 1.27 1.27)
					(thickness 0.15)
				)
			)
		)
		(property "Author" "Antmicro"
			(at 365.6125 -75.8225 0)
			(layer "B.Fab")
			(hide yes)
			(effects
				(font
					(size 1 1)
					(thickness 0.15)
				)
				(justify mirror)
			)
		)
		(property "License" "Apache-2.0"
			(at 365.6125 -75.8225 0)
			(layer "B.Fab")
			(hide yes)
			(effects
				(font
					(size 1 1)
					(thickness 0.15)
				)
				(justify mirror)
			)
		)
		(property "MPN" "CR0402-FX-1002GLF"
			(at 365.6125 -75.8225 0)
			(layer "B.Fab")
			(hide yes)
			(effects
				(font
					(size 1 1)
					(thickness 0.15)
				)
				(justify mirror)
			)
		)
		(property "Manufacturer" "Bourns"
			(at 365.6125 -75.8225 0)
			(layer "B.Fab")
			(hide yes)
			(effects
				(font
					(size 1 1)
					(thickness 0.15)
				)
				(justify mirror)
			)
		)
		(property "Public" ""
			(at 365.6125 -75.8225 0)
			(layer "B.Fab")
			(hide yes)
			(effects
				(font
					(size 1 1)
					(thickness 0.15)
				)
				(justify mirror)
			)
		)
		(property "Tolerance" "1%"
			(at 365.6125 -75.8225 0)
			(layer "B.Fab")
			(hide yes)
			(effects
				(font
					(size 1 1)
					(thickness 0.15)
				)
				(justify mirror)
			)
		)
		(property "Val" "10k"
			(at 365.6125 -75.8225 0)
			(layer "B.Fab")
			(hide yes)
			(effects
				(font
					(size 1 1)
					(thickness 0.15)
				)
				(justify mirror)
			)
		)
		(sheetname "/WiFi_Bluetooth/")
		(sheetfile "wifi_bt.kicad_sch")
		(attr smd)
		(fp_rect
			(start -0.925 0.47)
			(end 0.925 -0.47)
			(stroke
				(width 0.05)
				(type default)
			)
			(fill no)
			(layer "B.CrtYd")
		)
		(fp_rect
			(start -0.5 0.25)
			(end 0.5 -0.25)
			(stroke
				(width 0.15)
				(type solid)
			)
			(fill no)
			(layer "B.Fab")
		)
		(fp_text user "License: Apache-2.0"
			(at -0.95 -5.169 270)
			(layer "B.Fab")
			(effects
				(font
					(size 0.7 0.7)
					(thickness 0.15)
				)
				(justify left bottom mirror)
			)
		)
		(fp_text user "${REFERENCE}"
			(at -0.95 -3.168 270)
			(layer "B.Fab")
			(effects
				(font
					(size 0.7 0.7)
					(thickness 0.15)
				)
				(justify left bottom mirror)
			)
		)
		(fp_text user "Author: Antmicro"
			(at -0.95 -4.169 270)
			(layer "B.Fab")
			(effects
				(font
					(size 0.7 0.7)
					(thickness 0.15)
				)
				(justify left bottom mirror)
			)
		)
		(pad "1" smd roundrect
			(at -0.48 0 90)
			(size 0.59 0.64)
			(layers "B.Cu" "B.Mask" "B.Paste")
			(roundrect_rratio 0.25)
			(net 172 "BT_REG_ON")
			(pintype "passive")
		)
		(pad "2" smd roundrect
			(at 0.48 0 90)
			(size 0.59 0.64)
			(layers "B.Cu" "B.Mask" "B.Paste")
			(roundrect_rratio 0.25)
			(net 50 "+3V3")
			(pintype "passive")
		)
	)
	(footprint "antmicro-footprints:C_0402_1005Metric"
		(layer "B.Cu")
		(at 196.08 138.614 90)
		(descr "Capacitor SMD 0402")
		(tags "capacitor SMD 0402")
		(property "Reference" "C16"
			(at 4.939 -9.705 90)
			(layer "B.SilkS")
			(effects
				(font
					(size 0.7 0.7)
					(thickness 0.15)
				)
				(justify right bottom mirror)
			)
		)
		(property "Value" "C_100n_0402"
			(at -1.022927 -2.155213 90)
			(layer "B.Fab")
			(hide yes)
			(effects
				(font
					(size 0.7 0.7)
					(thickness 0.15)
				)
				(justify right bottom mirror)
			)
		)
		(property "Datasheet" "https://www.murata.com/products/productdetail?partno=GRM155R61H104KE14%23"
			(at 0 0 90)
			(layer "F.Fab")
			(hide yes)
			(effects
				(font
					(size 1.27 1.27)
					(thickness 0.15)
				)
			)
		)
		(property "Description" "SMD Multilayer Ceramic Capacitor, 0.1 µF, 50 V, 0402 [1005 Metric], ± 10%, X5R, GRM Series"
			(at 0 0 90)
			(layer "F.Fab")
			(hide yes)
			(effects
				(font
					(size 1.27 1.27)
					(thickness 0.15)
				)
			)
		)
		(property "Author" "Antmicro"
			(at 334.694 -57.466 0)
			(layer "B.Fab")
			(hide yes)
			(effects
				(font
					(size 1 1)
					(thickness 0.15)
				)
				(justify mirror)
			)
		)
		(property "Dielectric" "X5R"
			(at 334.694 -57.466 0)
			(layer "B.Fab")
			(hide yes)
			(effects
				(font
					(size 1 1)
					(thickness 0.15)
				)
				(justify mirror)
			)
		)
		(property "License" "Apache-2.0"
			(at 334.694 -57.466 0)
			(layer "B.Fab")
			(hide yes)
			(effects
				(font
					(size 1 1)
					(thickness 0.15)
				)
				(justify mirror)
			)
		)
		(property "MPN" "GRM155R61H104KE14D"
			(at 334.694 -57.466 0)
			(layer "B.Fab")
			(hide yes)
			(effects
				(font
					(size 1 1)
					(thickness 0.15)
				)
				(justify mirror)
			)
		)
		(property "Manufacturer" "Murata"
			(at 334.694 -57.466 0)
			(layer "B.Fab")
			(hide yes)
			(effects
				(font
					(size 1 1)
					(thickness 0.15)
				)
				(justify mirror)
			)
		)
		(property "Public" ""
			(at 334.694 -57.466 0)
			(layer "B.Fab")
			(hide yes)
			(effects
				(font
					(size 1 1)
					(thickness 0.15)
				)
				(justify mirror)
			)
		)
		(property "Val" "100n"
			(at 334.694 -57.466 0)
			(layer "B.Fab")
			(hide yes)
			(effects
				(font
					(size 1 1)
					(thickness 0.15)
				)
				(justify mirror)
			)
		)
		(property "Voltage" "50V"
			(at 334.694 -57.466 0)
			(layer "B.Fab")
			(hide yes)
			(effects
				(font
					(size 1 1)
					(thickness 0.15)
				)
				(justify mirror)
			)
		)
		(sheetname "/FPGA Supply/")
		(sheetfile "fpga-supply.kicad_sch")
		(attr smd)
		(fp_rect
			(start -0.925 0.47)
			(end 0.925 -0.47)
			(stroke
				(width 0.05)
				(type default)
			)
			(fill no)
			(layer "B.CrtYd")
		)
		(fp_line
			(start 0.504 -0.248)
			(end -0.494 -0.248)
			(stroke
				(width 0.15)
				(type solid)
			)
			(layer "B.Fab")
		)
		(fp_line
			(start -0.494 -0.248)
			(end -0.494 0.25)
			(stroke
				(width 0.15)
				(type solid)
			)
			(layer "B.Fab")
		)
		(fp_line
			(start 0.504 0.25)
			(end 0.504 -0.248)
			(stroke
				(width 0.15)
				(type solid)
			)
			(layer "B.Fab")
		)
		(fp_line
			(start -0.494 0.25)
			(end 0.504 0.25)
			(stroke
				(width 0.15)
				(type solid)
			)
			(layer "B.Fab")
		)
		(fp_text user "License: Apache-2.0"
			(at -0.939 -5.799 270)
			(layer "B.Fab")
			(effects
				(font
					(size 0.7 0.7)
					(thickness 0.15)
				)
				(justify left bottom mirror)
			)
		)
		(fp_text user "${REFERENCE}"
			(at -0.939 -4.599 270)
			(layer "B.Fab")
			(effects
				(font
					(size 0.7 0.7)
					(thickness 0.15)
				)
				(justify left bottom mirror)
			)
		)
		(fp_text user "Author: Antmicro"
			(at -0.939 -3.399 270)
			(layer "B.Fab")
			(effects
				(font
					(size 0.7 0.7)
					(thickness 0.15)
				)
				(justify left bottom mirror)
			)
		)
		(pad "1" smd roundrect
			(at -0.48 0 90)
			(size 0.59 0.64)
			(layers "B.Cu" "B.Mask" "B.Paste")
			(roundrect_rratio 0.25)
			(net 417 "GND")
			(pintype "passive")
		)
		(pad "2" smd roundrect
			(at 0.48 0 90)
			(size 0.59 0.64)
			(layers "B.Cu" "B.Mask" "B.Paste")
			(roundrect_rratio 0.25)
			(net 418 "+2V5")
			(pintype "passive")
		)
	)
	(footprint "antmicro-footprints:C_0402_1005Metric"
		(layer "B.Cu")
		(at 219.911 120.7394)
		(descr "Capacitor SMD 0402")
		(tags "capacitor SMD 0402")
		(property "Reference" "C224"
			(at 6.539 4.1106 0)
			(layer "B.SilkS")
			(effects
				(font
					(size 0.7 0.7)
					(thickness 0.15)
				)
				(justify right bottom mirror)
			)
		)
		(property "Value" "C_100n_0402"
			(at -1.022927 -2.155213 0)
			(layer "B.Fab")
			(hide yes)
			(effects
				(font
					(size 0.7 0.7)
					(thickness 0.15)
				)
				(justify right bottom mirror)
			)
		)
		(property "Datasheet" "https://www.murata.com/products/productdetail?partno=GRM155R61H104KE14%23"
			(at 0 0 0)
			(layer "F.Fab")
			(hide yes)
			(effects
				(font
					(size 1.27 1.27)
					(thickness 0.15)
				)
			)
		)
		(property "Description" "SMD Multilayer Ceramic Capacitor, 0.1 µF, 50 V, 0402 [1005 Metric], ± 10%, X5R, GRM Series"
			(at 0 0 0)
			(layer "F.Fab")
			(hide yes)
			(effects
				(font
					(size 1.27 1.27)
					(thickness 0.15)
				)
			)
		)
		(property "Author" "Antmicro"
			(at 0 0 0)
			(layer "B.Fab")
			(hide yes)
			(effects
				(font
					(size 1 1)
					(thickness 0.15)
				)
				(justify mirror)
			)
		)
		(property "Dielectric" "X5R"
			(at 0 0 0)
			(layer "B.Fab")
			(hide yes)
			(effects
				(font
					(size 1 1)
					(thickness 0.15)
				)
				(justify mirror)
			)
		)
		(property "License" "Apache-2.0"
			(at 0 0 0)
			(layer "B.Fab")
			(hide yes)
			(effects
				(font
					(size 1 1)
					(thickness 0.15)
				)
				(justify mirror)
			)
		)
		(property "MPN" "GRM155R61H104KE14D"
			(at 0 0 0)
			(layer "B.Fab")
			(hide yes)
			(effects
				(font
					(size 1 1)
					(thickness 0.15)
				)
				(justify mirror)
			)
		)
		(property "Manufacturer" "Murata"
			(at 0 0 0)
			(layer "B.Fab")
			(hide yes)
			(effects
				(font
					(size 1 1)
					(thickness 0.15)
				)
				(justify mirror)
			)
		)
		(property "Public" ""
			(at 0 0 0)
			(layer "B.Fab")
			(hide yes)
			(effects
				(font
					(size 1 1)
					(thickness 0.15)
				)
				(justify mirror)
			)
		)
		(property "Val" "100n"
			(at 0 0 0)
			(layer "B.Fab")
			(hide yes)
			(effects
				(font
					(size 1 1)
					(thickness 0.15)
				)
				(justify mirror)
			)
		)
		(property "Voltage" "50V"
			(at 0 0 0)
			(layer "B.Fab")
			(hide yes)
			(effects
				(font
					(size 1 1)
					(thickness 0.15)
				)
				(justify mirror)
			)
		)
		(sheetname "/Ethernet/")
		(sheetfile "ethernet.kicad_sch")
		(attr smd)
		(fp_rect
			(start -0.925 0.47)
			(end 0.925 -0.47)
			(stroke
				(width 0.05)
				(type default)
			)
			(fill no)
			(layer "B.CrtYd")
		)
		(fp_line
			(start -0.494 -0.248)
			(end -0.494 0.25)
			(stroke
				(width 0.15)
				(type solid)
			)
			(layer "B.Fab")
		)
		(fp_line
			(start -0.494 0.25)
			(end 0.504 0.25)
			(stroke
				(width 0.15)
				(type solid)
			)
			(layer "B.Fab")
		)
		(fp_line
			(start 0.504 -0.248)
			(end -0.494 -0.248)
			(stroke
				(width 0.15)
				(type solid)
			)
			(layer "B.Fab")
		)
		(fp_line
			(start 0.504 0.25)
			(end 0.504 -0.248)
			(stroke
				(width 0.15)
				(type solid)
			)
			(layer "B.Fab")
		)
		(fp_text user "Author: Antmicro"
			(at -0.939 -3.399 180)
			(layer "B.Fab")
			(effects
				(font
					(size 0.7 0.7)
					(thickness 0.15)
				)
				(justify left bottom mirror)
			)
		)
		(fp_text user "License: Apache-2.0"
			(at -0.939 -5.799 180)
			(layer "B.Fab")
			(effects
				(font
					(size 0.7 0.7)
					(thickness 0.15)
				)
				(justify left bottom mirror)
			)
		)
		(fp_text user "${REFERENCE}"
			(at -0.939 -4.599 180)
			(layer "B.Fab")
			(effects
				(font
					(size 0.7 0.7)
					(thickness 0.15)
				)
				(justify left bottom mirror)
			)
		)
		(pad "1" smd roundrect
			(at -0.48 0)
			(size 0.59 0.64)
			(layers "B.Cu" "B.Mask" "B.Paste")
			(roundrect_rratio 0.25)
			(net 417 "GND")
			(pintype "passive")
		)
		(pad "2" smd roundrect
			(at 0.48 0)
			(size 0.59 0.64)
			(layers "B.Cu" "B.Mask" "B.Paste")
			(roundrect_rratio 0.25)
			(net 47 "+1V05")
			(pintype "passive")
		)
	)
	(footprint "antmicro-footprints:C_0402_1005Metric"
		(layer "B.Cu")
		(at 185 140.9675 90)
		(descr "Capacitor SMD 0402")
		(tags "capacitor SMD 0402")
		(property "Reference" "C107"
			(at -1.7825 0.4 0)
			(layer "B.SilkS")
			(effects
				(font
					(size 0.7 0.7)
					(thickness 0.15)
				)
				(justify right bottom mirror)
			)
		)
		(property "Value" "C_22u_0402"
			(at -1.022927 -2.155213 90)
			(layer "B.Fab")
			(hide yes)
			(effects
				(font
					(size 0.7 0.7)
					(thickness 0.15)
				)
				(justify right bottom mirror)
			)
		)
		(property "Datasheet" "https://www.murata.com/products/productdetail?partno=GRM158R60J226ME01%23"
			(at 0 0 90)
			(layer "F.Fab")
			(hide yes)
			(effects
				(font
					(size 1.27 1.27)
					(thickness 0.15)
				)
			)
		)
		(property "Description" "SMD Multilayer Ceramic Capacitor, 22 uF, 4 V, 0402 [1005 Metric], X6S"
			(at 0 0 90)
			(layer "F.Fab")
			(hide yes)
			(effects
				(font
					(size 1.27 1.27)
					(thickness 0.15)
				)
			)
		)
		(property "Author" "Antmicro"
			(at 325.9675 -44.0325 0)
			(layer "B.Fab")
			(hide yes)
			(effects
				(font
					(size 1 1)
					(thickness 0.15)
				)
				(justify mirror)
			)
		)
		(property "Dielectric" ""
			(at 325.9675 -44.0325 0)
			(layer "B.Fab")
			(hide yes)
			(effects
				(font
					(size 1 1)
					(thickness 0.15)
				)
				(justify mirror)
			)
		)
		(property "License" "Apache-2.0"
			(at 325.9675 -44.0325 0)
			(layer "B.Fab")
			(hide yes)
			(effects
				(font
					(size 1 1)
					(thickness 0.15)
				)
				(justify mirror)
			)
		)
		(property "MPN" "GRM158R60J226ME01D"
			(at 325.9675 -44.0325 0)
			(layer "B.Fab")
			(hide yes)
			(effects
				(font
					(size 1 1)
					(thickness 0.15)
				)
				(justify mirror)
			)
		)
		(property "Manufacturer" "Murata"
			(at 325.9675 -44.0325 0)
			(layer "B.Fab")
			(hide yes)
			(effects
				(font
					(size 1 1)
					(thickness 0.15)
				)
				(justify mirror)
			)
		)
		(property "Public" ""
			(at 325.9675 -44.0325 0)
			(layer "B.Fab")
			(hide yes)
			(effects
				(font
					(size 1 1)
					(thickness 0.15)
				)
				(justify mirror)
			)
		)
		(property "Val" "22u"
			(at 325.9675 -44.0325 0)
			(layer "B.Fab")
			(hide yes)
			(effects
				(font
					(size 1 1)
					(thickness 0.15)
				)
				(justify mirror)
			)
		)
		(property "Voltage" ""
			(at 325.9675 -44.0325 0)
			(layer "B.Fab")
			(hide yes)
			(effects
				(font
					(size 1 1)
					(thickness 0.15)
				)
				(justify mirror)
			)
		)
		(sheetname "/Supply/")
		(sheetfile "supply.kicad_sch")
		(attr smd)
		(fp_rect
			(start -0.925 0.47)
			(end 0.925 -0.47)
			(stroke
				(width 0.05)
				(type default)
			)
			(fill no)
			(layer "B.CrtYd")
		)
		(fp_line
			(start 0.504 -0.248)
			(end -0.494 -0.248)
			(stroke
				(width 0.15)
				(type solid)
			)
			(layer "B.Fab")
		)
		(fp_line
			(start -0.494 -0.248)
			(end -0.494 0.25)
			(stroke
				(width 0.15)
				(type solid)
			)
			(layer "B.Fab")
		)
		(fp_line
			(start 0.504 0.25)
			(end 0.504 -0.248)
			(stroke
				(width 0.15)
				(type solid)
			)
			(layer "B.Fab")
		)
		(fp_line
			(start -0.494 0.25)
			(end 0.504 0.25)
			(stroke
				(width 0.15)
				(type solid)
			)
			(layer "B.Fab")
		)
		(fp_text user "${REFERENCE}"
			(at -0.939 -4.599 270)
			(layer "B.Fab")
			(effects
				(font
					(size 0.7 0.7)
					(thickness 0.15)
				)
				(justify left bottom mirror)
			)
		)
		(fp_text user "Author: Antmicro"
			(at -0.939 -3.399 270)
			(layer "B.Fab")
			(effects
				(font
					(size 0.7 0.7)
					(thickness 0.15)
				)
				(justify left bottom mirror)
			)
		)
		(fp_text user "License: Apache-2.0"
			(at -0.939 -5.799 270)
			(layer "B.Fab")
			(effects
				(font
					(size 0.7 0.7)
					(thickness 0.15)
				)
				(justify left bottom mirror)
			)
		)
		(pad "1" smd roundrect
			(at -0.48 0 90)
			(size 0.59 0.64)
			(layers "B.Cu" "B.Mask" "B.Paste")
			(roundrect_rratio 0.25)
			(net 417 "GND")
			(pintype "passive")
		)
		(pad "2" smd roundrect
			(at 0.48 0 90)
			(size 0.59 0.64)
			(layers "B.Cu" "B.Mask" "B.Paste")
			(roundrect_rratio 0.25)
			(net 272 "/Supply/SENSE3_P")
			(pintype "passive")
		)
	)
)
